(kicad_pcb
	(version 20260206)
	(generator "pcbnew")
	(generator_version "10.0")
	(general
		(thickness 1.6)
		(legacy_teardrops no)
	)
	(paper "A4")
	(title_block
		(title "12092022_DA0F0TMDCD0_F0T_Management_Board_D_brd_V3_OCP.brd")
		(comment 1 "Grand Teton / footprints 168-173 of 1440")
	)
	(layers
		(0 "F.Cu" signal "TOP")
		(4 "In1.Cu" signal "GND")
		(6 "In2.Cu" signal "IN1")
		(8 "In3.Cu" signal "GND1")
		(10 "In4.Cu" signal "IN2")
		(12 "In5.Cu" signal "VCC")
		(14 "In6.Cu" signal "VCC1")
		(16 "In7.Cu" signal "IN3")
		(18 "In8.Cu" signal "GND2")
		(20 "In9.Cu" signal "IN4")
		(22 "In10.Cu" signal "GND3")
		(2 "B.Cu" signal "BOTTOM")
		(9 "F.Adhes" user "F.Adhesive")
		(11 "B.Adhes" user "B.Adhesive")
		(13 "F.Paste" user "Package Geometry/Pastemask Top")
		(15 "B.Paste" user "Package Geometry/Pastemask Bottom")
		(5 "F.SilkS" user "Ref Des/Silkscreen Top")
		(7 "B.SilkS" user "Ref Des/Silkscreen Bottom")
		(1 "F.Mask" user "Board Geometry/Soldermask Top")
		(3 "B.Mask" user "Board Geometry/Soldermask Bottom")
		(17 "Dwgs.User" user "User.Drawings")
		(19 "Cmts.User" user "User.Comments")
		(21 "Eco1.User" user "User.Eco1")
		(23 "Eco2.User" user "User.Eco2")
		(25 "Edge.Cuts" user "Board Geometry/Outline")
		(27 "Margin" user)
		(31 "F.CrtYd" user "Package Geometry/Place Bound Top")
		(29 "B.CrtYd" user "Package Geometry/Place Bound Bottom")
		(35 "F.Fab" user "Ref Des/Assembly Top")
		(33 "B.Fab" user "Ref Des/Assembly Bottom")
	)
	(footprint ""
		(layer "F.Cu")
		(at 112.014 90.17 90)
		(property "Reference" "X18"
			(at -2.07137 1.0795 0)
			(unlocked yes)
			(layer "F.SilkS")
			(effects
				(font
					(size 0.7874 0.5842)
					(thickness 0.1524)
				)
				(justify left)
			)
		)
		(property "Value" ""
			(at 0 0 90)
			(layer "F.Fab")
			(effects
				(font
					(size 1.27 1.27)
				)
			)
		)
		(property "Device Type" "TP_TDR_4P_FTS_TH-TP_TDR_4P_DIPA"
			(at 1.30175 1.27 180)
			(unlocked yes)
			(layer "F.Fab")
			(hide yes)
			(effects
				(font
					(size 0.635 0.4064)
					(thickness 0.1524)
				)
			)
		)
		(property "User Part Number" "N_A"
			(at 1.30175 1.27 180)
			(unlocked yes)
			(layer "Cmts.User")
			(hide yes)
			(effects
				(font
					(size 0.635 0.4064)
					(thickness 0.1524)
				)
			)
		)
		(duplicate_pad_numbers_are_jumpers no)
		(fp_line
			(start 2.54 -1.27)
			(end 0 -1.27)
			(stroke
				(width 0.1524)
				(type default)
			)
			(layer "F.SilkS")
		)
		(fp_line
			(start 0 -1.27)
			(end 0 -0.635)
			(stroke
				(width 0.1524)
				(type default)
			)
			(layer "F.SilkS")
		)
		(fp_line
			(start 2.54 -1.1303)
			(end 2.54 -1.27)
			(stroke
				(width 0.1524)
				(type default)
			)
			(layer "F.SilkS")
		)
		(fp_line
			(start 0 0.635)
			(end 0 1.905)
			(stroke
				(width 0.1524)
				(type default)
			)
			(layer "F.SilkS")
		)
		(fp_line
			(start 2.54 1.4097)
			(end 2.54 1.1303)
			(stroke
				(width 0.1524)
				(type default)
			)
			(layer "F.SilkS")
		)
		(fp_line
			(start 0 3.175)
			(end 0 3.81)
			(stroke
				(width 0.1524)
				(type default)
			)
			(layer "F.SilkS")
		)
		(fp_line
			(start 2.54 3.81)
			(end 2.54 3.6703)
			(stroke
				(width 0.1524)
				(type default)
			)
			(layer "F.SilkS")
		)
		(fp_line
			(start 0 3.81)
			(end 2.54 3.81)
			(stroke
				(width 0.1524)
				(type default)
			)
			(layer "F.SilkS")
		)
		(fp_poly
			(pts
				(xy -0.761746 0) (xy -2.285746 -0.762) (xy -2.285746 0.762)
			)
			(stroke
				(width 0)
				(type default)
			)
			(fill yes)
			(layer "F.SilkS")
		)
		(fp_line
			(start 2.54 -1.27)
			(end 0 -1.27)
			(stroke
				(width 0.1)
				(type default)
			)
			(layer "F.Fab")
		)
		(fp_line
			(start 0 -1.27)
			(end 0 3.81)
			(stroke
				(width 0.1)
				(type default)
			)
			(layer "F.Fab")
		)
		(fp_line
			(start 2.54 3.81)
			(end 2.54 -1.27)
			(stroke
				(width 0.1)
				(type default)
			)
			(layer "F.Fab")
		)
		(fp_line
			(start 0 3.81)
			(end 2.54 3.81)
			(stroke
				(width 0.1)
				(type default)
			)
			(layer "F.Fab")
		)
		(fp_poly
			(pts
				(xy -0.761746 0) (xy -2.285746 -0.762) (xy -2.285746 0.762)
			)
			(stroke
				(width 0)
				(type default)
			)
			(fill yes)
			(layer "F.Fab")
		)
		(pad "1" thru_hole circle
			(at 0 0 90)
			(size 1.0033 1.0033)
			(drill 0.249936)
			(layers "*.Cu" "*.Mask")
			(remove_unused_layers no)
			(net "TDR_DIFF_100_BOT_DP")
			(clearance 0.10795)
			(thermal_gap 0.10795)
			(padstack
				(mode front_inner_back)
				(layer "Inner"
					(shape circle)
					(size 0.8001 0.8001)
					(clearance 0.1524)
				)
				(layer "B.Cu"
					(shape circle)
					(size 1.0033 1.0033)
					(clearance 0.10795)
				)
			)
		)
		(pad "2" thru_hole circle
			(at 2.54 0 90)
			(size 1.9939 1.9939)
			(drill 0.249936)
			(layers "*.Cu" "*.Mask")
			(remove_unused_layers no)
			(net "GND_P1")
			(clearance 0.10795)
			(thermal_gap 0.10795)
			(padstack
				(mode front_inner_back)
				(layer "Inner"
					(shape circle)
					(size 0.8001 0.8001)
					(clearance 0.1524)
				)
				(layer "B.Cu"
					(shape circle)
					(size 1.9939 1.9939)
					(clearance 0.10795)
				)
			)
		)
		(pad "3" thru_hole circle
			(at 2.54 2.54 90)
			(size 1.9939 1.9939)
			(drill 0.249936)
			(layers "*.Cu" "*.Mask")
			(remove_unused_layers no)
			(net "GND_P1")
			(clearance 0.10795)
			(thermal_gap 0.10795)
			(padstack
				(mode front_inner_back)
				(layer "Inner"
					(shape circle)
					(size 0.8001 0.8001)
					(clearance 0.1524)
				)
				(layer "B.Cu"
					(shape circle)
					(size 1.9939 1.9939)
					(clearance 0.10795)
				)
			)
		)
		(pad "4" thru_hole circle
			(at 0 2.54 90)
			(size 1.0033 1.0033)
			(drill 0.249936)
			(layers "*.Cu" "*.Mask")
			(remove_unused_layers no)
			(net "TDR_DIFF_100_BOT_DN")
			(clearance 0.10795)
			(thermal_gap 0.10795)
			(padstack
				(mode front_inner_back)
				(layer "Inner"
					(shape circle)
					(size 0.8001 0.8001)
					(clearance 0.1524)
				)
				(layer "B.Cu"
					(shape circle)
					(size 1.0033 1.0033)
					(clearance 0.10795)
				)
			)
		)
	)
	(footprint ""
		(layer "F.Cu")
		(at 31.56204 -70.536054 90)
		(property "Reference" "R660"
			(at 0 0 90)
			(layer "F.SilkS")
			(hide yes)
			(effects
				(font
					(size 1.27 1.27)
				)
			)
		)
		(property "Value" ""
			(at 0 0 90)
			(layer "F.Fab")
			(effects
				(font
					(size 1.27 1.27)
				)
			)
		)
		(duplicate_pad_numbers_are_jumpers no)
		(fp_line
			(start 0.7874 -0.4064)
			(end 0.7874 0.4064)
			(stroke
				(width 0.1524)
				(type default)
			)
			(layer "F.SilkS")
		)
		(fp_line
			(start -0.7874 -0.4064)
			(end 0.7874 -0.4064)
			(stroke
				(width 0.1524)
				(type default)
			)
			(layer "F.SilkS")
		)
		(fp_line
			(start 0.7874 0.4064)
			(end -0.7874 0.4064)
			(stroke
				(width 0.1524)
				(type default)
			)
			(layer "F.SilkS")
		)
		(fp_line
			(start -0.7874 0.4064)
			(end -0.7874 -0.4064)
			(stroke
				(width 0.1524)
				(type default)
			)
			(layer "F.SilkS")
		)
		(fp_line
			(start -0.12065 -0.305054)
			(end -0.12065 -0.2794)
			(stroke
				(width 0.1)
				(type default)
			)
			(layer "F.Fab")
		)
		(fp_line
			(start -0.67945 -0.305054)
			(end -0.12065 -0.305054)
			(stroke
				(width 0.1)
				(type default)
			)
			(layer "F.Fab")
		)
		(fp_line
			(start 0.67945 -0.3048)
			(end 0.67945 0.3048)
			(stroke
				(width 0.1)
				(type default)
			)
			(layer "F.Fab")
		)
		(fp_line
			(start 0.12065 -0.3048)
			(end 0.67945 -0.3048)
			(stroke
				(width 0.1)
				(type default)
			)
			(layer "F.Fab")
		)
		(fp_line
			(start 0.12065 -0.2794)
			(end 0.12065 -0.3048)
			(stroke
				(width 0.1)
				(type default)
			)
			(layer "F.Fab")
		)
		(fp_line
			(start -0.12065 -0.2794)
			(end 0.12065 -0.2794)
			(stroke
				(width 0.1)
				(type default)
			)
			(layer "F.Fab")
		)
		(fp_line
			(start 0.120396 0.2794)
			(end -0.12065 0.2794)
			(stroke
				(width 0.1)
				(type default)
			)
			(layer "F.Fab")
		)
		(fp_line
			(start -0.12065 0.2794)
			(end -0.12065 0.3048)
			(stroke
				(width 0.1)
				(type default)
			)
			(layer "F.Fab")
		)
		(fp_line
			(start 0.67945 0.3048)
			(end 0.120396 0.3048)
			(stroke
				(width 0.1)
				(type default)
			)
			(layer "F.Fab")
		)
		(fp_line
			(start 0.120396 0.3048)
			(end 0.120396 0.2794)
			(stroke
				(width 0.1)
				(type default)
			)
			(layer "F.Fab")
		)
		(fp_line
			(start -0.12065 0.3048)
			(end -0.67945 0.3048)
			(stroke
				(width 0.1)
				(type default)
			)
			(layer "F.Fab")
		)
		(fp_line
			(start -0.67945 0.3048)
			(end -0.67945 -0.305054)
			(stroke
				(width 0.1)
				(type default)
			)
			(layer "F.Fab")
		)
		(pad "1" smd circle
			(at -0.40005 0 90)
			(size 0 0)
			(layers "F.Cu" "F.Mask" "F.Paste")
			(net "P3V3_AUX")
		)
		(pad "2" smd circle
			(at 0.40005 0 90)
			(size 0 0)
			(layers "F.Cu" "F.Mask" "F.Paste")
			(net "EMMC_DT5_R")
		)
	)
	(footprint ""
		(layer "F.Cu")
		(at 84.795106 -70.458838 90)
		(property "Reference" "PR539"
			(at 0 0 90)
			(layer "F.SilkS")
			(hide yes)
			(effects
				(font
					(size 1.27 1.27)
				)
			)
		)
		(property "Value" ""
			(at 0 0 90)
			(layer "F.Fab")
			(effects
				(font
					(size 1.27 1.27)
				)
			)
		)
		(duplicate_pad_numbers_are_jumpers no)
		(fp_line
			(start 0.7874 -0.4064)
			(end 0.7874 0.4064)
			(stroke
				(width 0.1524)
				(type default)
			)
			(layer "F.SilkS")
		)
		(fp_line
			(start -0.7874 -0.4064)
			(end 0.7874 -0.4064)
			(stroke
				(width 0.1524)
				(type default)
			)
			(layer "F.SilkS")
		)
		(fp_line
			(start 0.7874 0.4064)
			(end -0.7874 0.4064)
			(stroke
				(width 0.1524)
				(type default)
			)
			(layer "F.SilkS")
		)
		(fp_line
			(start -0.7874 0.4064)
			(end -0.7874 -0.4064)
			(stroke
				(width 0.1524)
				(type default)
			)
			(layer "F.SilkS")
		)
		(fp_line
			(start -0.12065 -0.305054)
			(end -0.12065 -0.2794)
			(stroke
				(width 0.1)
				(type default)
			)
			(layer "F.Fab")
		)
		(fp_line
			(start -0.67945 -0.305054)
			(end -0.12065 -0.305054)
			(stroke
				(width 0.1)
				(type default)
			)
			(layer "F.Fab")
		)
		(fp_line
			(start 0.67945 -0.3048)
			(end 0.67945 0.3048)
			(stroke
				(width 0.1)
				(type default)
			)
			(layer "F.Fab")
		)
		(fp_line
			(start 0.12065 -0.3048)
			(end 0.67945 -0.3048)
			(stroke
				(width 0.1)
				(type default)
			)
			(layer "F.Fab")
		)
		(fp_line
			(start 0.12065 -0.2794)
			(end 0.12065 -0.3048)
			(stroke
				(width 0.1)
				(type default)
			)
			(layer "F.Fab")
		)
		(fp_line
			(start -0.12065 -0.2794)
			(end 0.12065 -0.2794)
			(stroke
				(width 0.1)
				(type default)
			)
			(layer "F.Fab")
		)
		(fp_line
			(start 0.120396 0.2794)
			(end -0.12065 0.2794)
			(stroke
				(width 0.1)
				(type default)
			)
			(layer "F.Fab")
		)
		(fp_line
			(start -0.12065 0.2794)
			(end -0.12065 0.3048)
			(stroke
				(width 0.1)
				(type default)
			)
			(layer "F.Fab")
		)
		(fp_line
			(start 0.67945 0.3048)
			(end 0.120396 0.3048)
			(stroke
				(width 0.1)
				(type default)
			)
			(layer "F.Fab")
		)
		(fp_line
			(start 0.120396 0.3048)
			(end 0.120396 0.2794)
			(stroke
				(width 0.1)
				(type default)
			)
			(layer "F.Fab")
		)
		(fp_line
			(start -0.12065 0.3048)
			(end -0.67945 0.3048)
			(stroke
				(width 0.1)
				(type default)
			)
			(layer "F.Fab")
		)
		(fp_line
			(start -0.67945 0.3048)
			(end -0.67945 -0.305054)
			(stroke
				(width 0.1)
				(type default)
			)
			(layer "F.Fab")
		)
		(pad "1" smd circle
			(at -0.40005 0 90)
			(size 0 0)
			(layers "F.Cu" "F.Mask" "F.Paste")
			(net "PVCC1_AUX")
		)
		(pad "2" smd circle
			(at 0.40005 0 90)
			(size 0 0)
			(layers "F.Cu" "F.Mask" "F.Paste")
			(net "P1V2_AUX_VCC")
		)
	)
	(footprint ""
		(layer "F.Cu")
		(at 64.1096 -70.84314 90)
		(property "Reference" "R96"
			(at 0 0 90)
			(layer "F.SilkS")
			(hide yes)
			(effects
				(font
					(size 1.27 1.27)
				)
			)
		)
		(property "Value" ""
			(at 0 0 90)
			(layer "F.Fab")
			(effects
				(font
					(size 1.27 1.27)
				)
			)
		)
		(duplicate_pad_numbers_are_jumpers no)
		(fp_line
			(start 0.7874 -0.4064)
			(end 0.7874 0.4064)
			(stroke
				(width 0.1524)
				(type default)
			)
			(layer "F.SilkS")
		)
		(fp_line
			(start -0.7874 -0.4064)
			(end 0.7874 -0.4064)
			(stroke
				(width 0.1524)
				(type default)
			)
			(layer "F.SilkS")
		)
		(fp_line
			(start 0.7874 0.4064)
			(end -0.7874 0.4064)
			(stroke
				(width 0.1524)
				(type default)
			)
			(layer "F.SilkS")
		)
		(fp_line
			(start -0.7874 0.4064)
			(end -0.7874 -0.4064)
			(stroke
				(width 0.1524)
				(type default)
			)
			(layer "F.SilkS")
		)
		(fp_line
			(start -0.12065 -0.305054)
			(end -0.12065 -0.2794)
			(stroke
				(width 0.1)
				(type default)
			)
			(layer "F.Fab")
		)
		(fp_line
			(start -0.67945 -0.305054)
			(end -0.12065 -0.305054)
			(stroke
				(width 0.1)
				(type default)
			)
			(layer "F.Fab")
		)
		(fp_line
			(start 0.67945 -0.3048)
			(end 0.67945 0.3048)
			(stroke
				(width 0.1)
				(type default)
			)
			(layer "F.Fab")
		)
		(fp_line
			(start 0.12065 -0.3048)
			(end 0.67945 -0.3048)
			(stroke
				(width 0.1)
				(type default)
			)
			(layer "F.Fab")
		)
		(fp_line
			(start 0.12065 -0.2794)
			(end 0.12065 -0.3048)
			(stroke
				(width 0.1)
				(type default)
			)
			(layer "F.Fab")
		)
		(fp_line
			(start -0.12065 -0.2794)
			(end 0.12065 -0.2794)
			(stroke
				(width 0.1)
				(type default)
			)
			(layer "F.Fab")
		)
		(fp_line
			(start 0.120396 0.2794)
			(end -0.12065 0.2794)
			(stroke
				(width 0.1)
				(type default)
			)
			(layer "F.Fab")
		)
		(fp_line
			(start -0.12065 0.2794)
			(end -0.12065 0.3048)
			(stroke
				(width 0.1)
				(type default)
			)
			(layer "F.Fab")
		)
		(fp_line
			(start 0.67945 0.3048)
			(end 0.120396 0.3048)
			(stroke
				(width 0.1)
				(type default)
			)
			(layer "F.Fab")
		)
		(fp_line
			(start 0.120396 0.3048)
			(end 0.120396 0.2794)
			(stroke
				(width 0.1)
				(type default)
			)
			(layer "F.Fab")
		)
		(fp_line
			(start -0.12065 0.3048)
			(end -0.67945 0.3048)
			(stroke
				(width 0.1)
				(type default)
			)
			(layer "F.Fab")
		)
		(fp_line
			(start -0.67945 0.3048)
			(end -0.67945 -0.305054)
			(stroke
				(width 0.1)
				(type default)
			)
			(layer "F.Fab")
		)
		(pad "1" smd circle
			(at -0.40005 0 90)
			(size 0 0)
			(layers "F.Cu" "F.Mask" "F.Paste")
			(net "BMC_EMMC_RST_R_N")
		)
		(pad "2" smd circle
			(at 0.40005 0 90)
			(size 0 0)
			(layers "F.Cu" "F.Mask" "F.Paste")
			(net "BMC_EMMC_RST_N")
		)
	)
	(footprint ""
		(layer "F.Cu")
		(at 71.80834 -23.68804 180)
		(property "Reference" "R585"
			(at 0 0 180)
			(layer "F.SilkS")
			(hide yes)
			(effects
				(font
					(size 1.27 1.27)
				)
			)
		)
		(property "Value" ""
			(at 0 0 180)
			(layer "F.Fab")
			(effects
				(font
					(size 1.27 1.27)
				)
			)
		)
		(duplicate_pad_numbers_are_jumpers no)
		(fp_line
			(start 0.7874 0.4064)
			(end -0.7874 0.4064)
			(stroke
				(width 0.1524)
				(type default)
			)
			(layer "F.SilkS")
		)
		(fp_line
			(start 0.7874 -0.4064)
			(end 0.7874 0.4064)
			(stroke
				(width 0.1524)
				(type default)
			)
			(layer "F.SilkS")
		)
		(fp_line
			(start -0.7874 0.4064)
			(end -0.7874 -0.4064)
			(stroke
				(width 0.1524)
				(type default)
			)
			(layer "F.SilkS")
		)
		(fp_line
			(start -0.7874 -0.4064)
			(end 0.7874 -0.4064)
			(stroke
				(width 0.1524)
				(type default)
			)
			(layer "F.SilkS")
		)
		(fp_line
			(start 0.67945 0.3048)
			(end 0.120396 0.3048)
			(stroke
				(width 0.1)
				(type default)
			)
			(layer "F.Fab")
		)
		(fp_line
			(start 0.67945 -0.3048)
			(end 0.67945 0.3048)
			(stroke
				(width 0.1)
				(type default)
			)
			(layer "F.Fab")
		)
		(fp_line
			(start 0.12065 -0.2794)
			(end 0.12065 -0.3048)
			(stroke
				(width 0.1)
				(type default)
			)
			(layer "F.Fab")
		)
		(fp_line
			(start 0.12065 -0.3048)
			(end 0.67945 -0.3048)
			(stroke
				(width 0.1)
				(type default)
			)
			(layer "F.Fab")
		)
		(fp_line
			(start 0.120396 0.3048)
			(end 0.120396 0.2794)
			(stroke
				(width 0.1)
				(type default)
			)
			(layer "F.Fab")
		)
		(fp_line
			(start 0.120396 0.2794)
			(end -0.12065 0.2794)
			(stroke
				(width 0.1)
				(type default)
			)
			(layer "F.Fab")
		)
		(fp_line
			(start -0.12065 0.3048)
			(end -0.67945 0.3048)
			(stroke
				(width 0.1)
				(type default)
			)
			(layer "F.Fab")
		)
		(fp_line
			(start -0.12065 0.2794)
			(end -0.12065 0.3048)
			(stroke
				(width 0.1)
				(type default)
			)
			(layer "F.Fab")
		)
		(fp_line
			(start -0.12065 -0.2794)
			(end 0.12065 -0.2794)
			(stroke
				(width 0.1)
				(type default)
			)
			(layer "F.Fab")
		)
		(fp_line
			(start -0.12065 -0.305054)
			(end -0.12065 -0.2794)
			(stroke
				(width 0.1)
				(type default)
			)
			(layer "F.Fab")
		)
		(fp_line
			(start -0.67945 0.3048)
			(end -0.67945 -0.305054)
			(stroke
				(width 0.1)
				(type default)
			)
			(layer "F.Fab")
		)
		(fp_line
			(start -0.67945 -0.305054)
			(end -0.12065 -0.305054)
			(stroke
				(width 0.1)
				(type default)
			)
			(layer "F.Fab")
		)
		(pad "1" smd circle
			(at -0.40005 0 180)
			(size 0 0)
			(layers "F.Cu" "F.Mask" "F.Paste")
			(net "BMC_RSTIND_N")
		)
		(pad "2" smd circle
			(at 0.40005 0 180)
			(size 0 0)
			(layers "F.Cu" "F.Mask" "F.Paste")
			(net "RST_SPI_FLASH_N")
		)
	)
	(footprint ""
		(layer "F.Cu")
		(at 46.9646 -76.2508)
		(property "Reference" "R181"
			(at 0 0 0)
			(layer "F.SilkS")
			(hide yes)
			(effects
				(font
					(size 1.27 1.27)
				)
			)
		)
		(property "Value" ""
			(at 0 0 0)
			(layer "F.Fab")
			(effects
				(font
					(size 1.27 1.27)
				)
			)
		)
		(duplicate_pad_numbers_are_jumpers no)
		(fp_line
			(start -0.7874 -0.4064)
			(end 0.7874 -0.4064)
			(stroke
				(width 0.1524)
				(type default)
			)
			(layer "F.SilkS")
		)
		(fp_line
			(start -0.7874 0.4064)
			(end -0.7874 -0.4064)
			(stroke
				(width 0.1524)
				(type default)
			)
			(layer "F.SilkS")
		)
		(fp_line
			(start 0.7874 -0.4064)
			(end 0.7874 0.4064)
			(stroke
				(width 0.1524)
				(type default)
			)
			(layer "F.SilkS")
		)
		(fp_line
			(start 0.7874 0.4064)
			(end -0.7874 0.4064)
			(stroke
				(width 0.1524)
				(type default)
			)
			(layer "F.SilkS")
		)
		(fp_line
			(start -0.67945 -0.305054)
			(end -0.12065 -0.305054)
			(stroke
				(width 0.1)
				(type default)
			)
			(layer "F.Fab")
		)
		(fp_line
			(start -0.67945 0.3048)
			(end -0.67945 -0.305054)
			(stroke
				(width 0.1)
				(type default)
			)
			(layer "F.Fab")
		)
		(fp_line
			(start -0.12065 -0.305054)
			(end -0.12065 -0.2794)
			(stroke
				(width 0.1)
				(type default)
			)
			(layer "F.Fab")
		)
		(fp_line
			(start -0.12065 -0.2794)
			(end 0.12065 -0.2794)
			(stroke
				(width 0.1)
				(type default)
			)
			(layer "F.Fab")
		)
		(fp_line
			(start -0.12065 0.2794)
			(end -0.12065 0.3048)
			(stroke
				(width 0.1)
				(type default)
			)
			(layer "F.Fab")
		)
		(fp_line
			(start -0.12065 0.3048)
			(end -0.67945 0.3048)
			(stroke
				(width 0.1)
				(type default)
			)
			(layer "F.Fab")
		)
		(fp_line
			(start 0.120396 0.2794)
			(end -0.12065 0.2794)
			(stroke
				(width 0.1)
				(type default)
			)
			(layer "F.Fab")
		)
		(fp_line
			(start 0.120396 0.3048)
			(end 0.120396 0.2794)
			(stroke
				(width 0.1)
				(type default)
			)
			(layer "F.Fab")
		)
		(fp_line
			(start 0.12065 -0.3048)
			(end 0.67945 -0.3048)
			(stroke
				(width 0.1)
				(type default)
			)
			(layer "F.Fab")
		)
		(fp_line
			(start 0.12065 -0.2794)
			(end 0.12065 -0.3048)
			(stroke
				(width 0.1)
				(type default)
			)
			(layer "F.Fab")
		)
		(fp_line
			(start 0.67945 -0.3048)
			(end 0.67945 0.3048)
			(stroke
				(width 0.1)
				(type default)
			)
			(layer "F.Fab")
		)
		(fp_line
			(start 0.67945 0.3048)
			(end 0.120396 0.3048)
			(stroke
				(width 0.1)
				(type default)
			)
			(layer "F.Fab")
		)
		(pad "1" smd circle
			(at -0.40005 0)
			(size 0 0)
			(layers "F.Cu" "F.Mask" "F.Paste")
			(net "P3V3_AUX")
		)
		(pad "2" smd circle
			(at 0.40005 0)
			(size 0 0)
			(layers "F.Cu" "F.Mask" "F.Paste")
			(net "FM_FLASH_LATCH_N")
		)
	)
)
